(kicad_pcb
	(version 20260206)
	(generator "pcbnew")
	(generator_version "10.0")
	(general
		(thickness 1.6)
		(legacy_teardrops no)
	)
	(paper "A4")
	(title_block
		(title "01162023_DA0F0TEBIF0_F0T_Expander_BD_F_brd_V02_OCP.brd")
		(comment 1 "Grand Teton / footprints 1502-1506 of 9728")
	)
	(layers
		(0 "F.Cu" signal "TOP")
		(4 "In1.Cu" signal "GND")
		(6 "In2.Cu" signal "VCC")
		(8 "In3.Cu" signal "VCC1")
		(10 "In4.Cu" signal "GND1")
		(12 "In5.Cu" signal "IN1")
		(14 "In6.Cu" signal "GND2")
		(16 "In7.Cu" signal "IN2")
		(18 "In8.Cu" signal "GND3")
		(20 "In9.Cu" signal "IN3")
		(22 "In10.Cu" signal "GND4")
		(24 "In11.Cu" signal "IN4")
		(26 "In12.Cu" signal "GND5")
		(28 "In13.Cu" signal "IN5")
		(30 "In14.Cu" signal "GND6")
		(32 "In15.Cu" signal "IN6")
		(34 "In16.Cu" signal "GND7")
		(2 "B.Cu" signal "BOTTOM")
		(9 "F.Adhes" user "F.Adhesive")
		(11 "B.Adhes" user "B.Adhesive")
		(13 "F.Paste" user "Package Geometry/Pastemask Top")
		(15 "B.Paste" user "Package Geometry/Pastemask Bottom")
		(5 "F.SilkS" user "Ref Des/Silkscreen Top")
		(7 "B.SilkS" user "Ref Des/Silkscreen Bottom")
		(1 "F.Mask" user "Board Geometry/Soldermask Top")
		(3 "B.Mask" user "Board Geometry/Soldermask Bottom")
		(17 "Dwgs.User" user "User.Drawings")
		(19 "Cmts.User" user "User.Comments")
		(21 "Eco1.User" user "User.Eco1")
		(23 "Eco2.User" user "User.Eco2")
		(25 "Edge.Cuts" user "Board Geometry/Outline")
		(27 "Margin" user)
		(31 "F.CrtYd" user "Package Geometry/Place Bound Top")
		(29 "B.CrtYd" user "Package Geometry/Place Bound Bottom")
		(35 "F.Fab" user "Ref Des/Assembly Top")
		(33 "B.Fab" user "Ref Des/Assembly Bottom")
	)
	(footprint ""
		(layer "F.Cu")
		(at 455.14006 -308.692042 180)
		(property "Reference" "PU19"
			(at 3.652012 -4.026662 0)
			(unlocked yes)
			(layer "F.SilkS")
			(effects
				(font
					(size 0.7874 0.5842)
					(thickness 0.1524)
				)
				(justify left)
			)
		)
		(property "Value" ""
			(at 0 0 180)
			(layer "F.Fab")
			(effects
				(font
					(size 1.27 1.27)
				)
			)
		)
		(duplicate_pad_numbers_are_jumpers no)
		(fp_line
			(start 1.549908 2.050034)
			(end 1.549908 1.9304)
			(stroke
				(width 0.1524)
				(type default)
			)
			(layer "F.SilkS")
		)
		(fp_line
			(start 1.549908 -1.9812)
			(end 1.549908 -2.050034)
			(stroke
				(width 0.1524)
				(type default)
			)
			(layer "F.SilkS")
		)
		(fp_line
			(start 1.549908 -2.050034)
			(end 0.5842 -2.050034)
			(stroke
				(width 0.1524)
				(type default)
			)
			(layer "F.SilkS")
		)
		(fp_line
			(start 0.3048 -2.4638)
			(end 0.3048 -3.2258)
			(stroke
				(width 0.1524)
				(type default)
			)
			(layer "F.SilkS")
		)
		(fp_line
			(start 0 2.050034)
			(end 1.549908 2.050034)
			(stroke
				(width 0.1524)
				(type default)
			)
			(layer "F.SilkS")
		)
		(fp_line
			(start -0.3048 2.4638)
			(end -0.3048 3.2258)
			(stroke
				(width 0.1524)
				(type default)
			)
			(layer "F.SilkS")
		)
		(fp_line
			(start -0.5842 -2.050034)
			(end -1.549908 -2.050034)
			(stroke
				(width 0.1524)
				(type default)
			)
			(layer "F.SilkS")
		)
		(fp_line
			(start -1.549908 2.050034)
			(end -0.5842 2.050034)
			(stroke
				(width 0.1524)
				(type default)
			)
			(layer "F.SilkS")
		)
		(fp_line
			(start -1.549908 1.9812)
			(end -1.549908 2.050034)
			(stroke
				(width 0.1524)
				(type default)
			)
			(layer "F.SilkS")
		)
		(fp_line
			(start -1.549908 -2.050034)
			(end -1.549908 -1.9812)
			(stroke
				(width 0.1524)
				(type default)
			)
			(layer "F.SilkS")
		)
		(fp_line
			(start -1.9812 0)
			(end -2.3622 0)
			(stroke
				(width 0.1524)
				(type default)
			)
			(layer "F.SilkS")
		)
		(fp_poly
			(pts
				(xy -2.9464 -2.208022) (xy -2.9464 -1.192022) (xy -1.9304 -1.700022)
			)
			(stroke
				(width 0)
				(type default)
			)
			(fill yes)
			(layer "F.SilkS")
		)
		(fp_line
			(start 1.549908 2.050034)
			(end 1.549908 -2.050034)
			(stroke
				(width 0.1)
				(type default)
			)
			(layer "F.Fab")
		)
		(fp_line
			(start 1.549908 -2.050034)
			(end -1.549908 -2.050034)
			(stroke
				(width 0.1)
				(type default)
			)
			(layer "F.Fab")
		)
		(fp_line
			(start 0.3048 -2.4638)
			(end 0.3048 -3.2258)
			(stroke
				(width 0.1)
				(type default)
			)
			(layer "F.Fab")
		)
		(fp_line
			(start -0.3048 2.4638)
			(end -0.3048 3.2258)
			(stroke
				(width 0.1)
				(type default)
			)
			(layer "F.Fab")
		)
		(fp_line
			(start -1.549908 2.050034)
			(end 1.549908 2.050034)
			(stroke
				(width 0.1)
				(type default)
			)
			(layer "F.Fab")
		)
		(fp_line
			(start -1.549908 -2.050034)
			(end -1.549908 2.050034)
			(stroke
				(width 0.1)
				(type default)
			)
			(layer "F.Fab")
		)
		(fp_line
			(start -1.9812 0)
			(end -2.3622 0)
			(stroke
				(width 0.1)
				(type default)
			)
			(layer "F.Fab")
		)
		(fp_poly
			(pts
				(xy -2.9464 -2.208022) (xy -2.9464 -1.192022) (xy -1.9304 -1.700022)
			)
			(stroke
				(width 0)
				(type default)
			)
			(fill yes)
			(layer "F.Fab")
		)
		(fp_text user "11_18"
			(at 2.512568 0.9906 90)
			(unlocked yes)
			(layer "F.SilkS")
			(effects
				(font
					(size 0.635 0.4064)
					(thickness 0.1524)
				)
			)
		)
		(fp_text user "19"
			(at 1.952498 -2.562606 90)
			(unlocked yes)
			(layer "F.SilkS")
			(effects
				(font
					(size 0.635 0.4064)
					(thickness 0.1524)
				)
			)
		)
		(fp_text user "9"
			(at -2.338832 2.0574 90)
			(unlocked yes)
			(layer "F.SilkS")
			(effects
				(font
					(size 0.635 0.4064)
					(thickness 0.1524)
				)
			)
		)
		(fp_text user "11_18"
			(at 2.512568 0.9906 90)
			(unlocked yes)
			(layer "F.Fab")
			(effects
				(font
					(size 0.635 0.4064)
					(thickness 0.1524)
				)
			)
		)
		(fp_text user "19"
			(at 2.410968 -2.159 90)
			(unlocked yes)
			(layer "F.Fab")
			(effects
				(font
					(size 0.635 0.4064)
					(thickness 0.1524)
				)
			)
		)
		(fp_text user "9"
			(at -2.338832 2.0574 90)
			(unlocked yes)
			(layer "F.Fab")
			(effects
				(font
					(size 0.635 0.4064)
					(thickness 0.1524)
				)
			)
		)
		(pad "1" smd rect
			(at -1.35001 -1.700022 270)
			(size 0.3048 0.9144)
			(layers "F.Cu" "F.Mask" "F.Paste")
			(net "SW_P1V25_PEX3_BT")
		)
		(pad "2" smd rect
			(at -1.400048 -1.199896 270)
			(size 0.1778 0.8128)
			(layers "F.Cu" "F.Mask" "F.Paste")
			(net "GND")
		)
		(pad "3" smd rect
			(at -1.400048 -0.8001 270)
			(size 0.1778 0.8128)
			(layers "F.Cu" "F.Mask" "F.Paste")
			(net "P1V25_PEX3_CS")
		)
		(pad "4" smd rect
			(at -1.400048 -0.40005 270)
			(size 0.1778 0.8128)
			(layers "F.Cu" "F.Mask" "F.Paste")
			(net "GND")
		)
		(pad "5" smd rect
			(at -1.400048 0 270)
			(size 0.1778 0.8128)
			(layers "F.Cu" "F.Mask" "F.Paste")
			(net "P1V25_PEX3_REF")
		)
		(pad "6" smd rect
			(at -1.400048 0.40005 270)
			(size 0.1778 0.8128)
			(layers "F.Cu" "F.Mask" "F.Paste")
			(net "SH_P1V25_PEX3_FB_N")
		)
		(pad "7" smd rect
			(at -1.400048 0.8001 270)
			(size 0.1778 0.8128)
			(layers "F.Cu" "F.Mask" "F.Paste")
			(net "P1V25_PEX3_FB")
		)
		(pad "8" smd rect
			(at -1.400048 1.199896 270)
			(size 0.1778 0.8128)
			(layers "F.Cu" "F.Mask" "F.Paste")
			(net "P1V25_PEX3_EN")
		)
		(pad "9" smd rect
			(at -1.400048 1.700022 270)
			(size 0.3048 0.8128)
			(layers "F.Cu" "F.Mask" "F.Paste")
			(net "PWRGD_P1V25_PEX3")
		)
		(pad "10" smd rect
			(at -0.299974 1.299972 180)
			(size 0.3048 2.0066)
			(layers "F.Cu" "F.Mask" "F.Paste")
			(net "SW_P12V_P1V25_PEX3_FLT")
		)
		(pad "11_18" smd circle
			(at 1.175004 0.275082 180)
			(size 0 0)
			(layers "F.Cu" "F.Mask" "F.Paste")
			(net "GND")
		)
		(pad "19" smd rect
			(at 1.400048 -1.700022 90)
			(size 0.3048 0.8128)
			(layers "F.Cu" "F.Mask" "F.Paste")
			(net "P1V25_PEX3_VCC")
		)
		(pad "20" smd rect
			(at 0.299974 -1.299972 180)
			(size 0.3048 2.0066)
			(layers "F.Cu" "F.Mask" "F.Paste")
			(net "SW_P1V25_PEX3_PH")
		)
		(pad "21" smd rect
			(at -0.299974 -1.299972 180)
			(size 0.3048 2.0066)
			(layers "F.Cu" "F.Mask" "F.Paste")
			(net "SW_P12V_P1V25_PEX3_FLT")
		)
	)
	(footprint ""
		(layer "F.Cu")
		(at 37.550344 -250.070874 -90)
		(property "Reference" "R1164"
			(at 0 0 270)
			(layer "F.SilkS")
			(hide yes)
			(effects
				(font
					(size 1.27 1.27)
				)
			)
		)
		(property "Value" ""
			(at 0 0 270)
			(layer "F.Fab")
			(effects
				(font
					(size 1.27 1.27)
				)
			)
		)
		(duplicate_pad_numbers_are_jumpers no)
		(fp_line
			(start -0.7874 0.4064)
			(end -0.7874 -0.4064)
			(stroke
				(width 0.1524)
				(type default)
			)
			(layer "F.SilkS")
		)
		(fp_line
			(start 0.7874 0.4064)
			(end -0.7874 0.4064)
			(stroke
				(width 0.1524)
				(type default)
			)
			(layer "F.SilkS")
		)
		(fp_line
			(start -0.7874 -0.4064)
			(end 0.7874 -0.4064)
			(stroke
				(width 0.1524)
				(type default)
			)
			(layer "F.SilkS")
		)
		(fp_line
			(start 0.7874 -0.4064)
			(end 0.7874 0.4064)
			(stroke
				(width 0.1524)
				(type default)
			)
			(layer "F.SilkS")
		)
		(fp_line
			(start -0.67945 0.3048)
			(end -0.67945 -0.305054)
			(stroke
				(width 0.1)
				(type default)
			)
			(layer "F.Fab")
		)
		(fp_line
			(start -0.12065 0.3048)
			(end -0.67945 0.3048)
			(stroke
				(width 0.1)
				(type default)
			)
			(layer "F.Fab")
		)
		(fp_line
			(start 0.120396 0.3048)
			(end 0.120396 0.2794)
			(stroke
				(width 0.1)
				(type default)
			)
			(layer "F.Fab")
		)
		(fp_line
			(start 0.67945 0.3048)
			(end 0.120396 0.3048)
			(stroke
				(width 0.1)
				(type default)
			)
			(layer "F.Fab")
		)
		(fp_line
			(start -0.12065 0.2794)
			(end -0.12065 0.3048)
			(stroke
				(width 0.1)
				(type default)
			)
			(layer "F.Fab")
		)
		(fp_line
			(start 0.120396 0.2794)
			(end -0.12065 0.2794)
			(stroke
				(width 0.1)
				(type default)
			)
			(layer "F.Fab")
		)
		(fp_line
			(start -0.12065 -0.2794)
			(end 0.12065 -0.2794)
			(stroke
				(width 0.1)
				(type default)
			)
			(layer "F.Fab")
		)
		(fp_line
			(start 0.12065 -0.2794)
			(end 0.12065 -0.3048)
			(stroke
				(width 0.1)
				(type default)
			)
			(layer "F.Fab")
		)
		(fp_line
			(start 0.12065 -0.3048)
			(end 0.67945 -0.3048)
			(stroke
				(width 0.1)
				(type default)
			)
			(layer "F.Fab")
		)
		(fp_line
			(start 0.67945 -0.3048)
			(end 0.67945 0.3048)
			(stroke
				(width 0.1)
				(type default)
			)
			(layer "F.Fab")
		)
		(fp_line
			(start -0.67945 -0.305054)
			(end -0.12065 -0.305054)
			(stroke
				(width 0.1)
				(type default)
			)
			(layer "F.Fab")
		)
		(fp_line
			(start -0.12065 -0.305054)
			(end -0.12065 -0.2794)
			(stroke
				(width 0.1)
				(type default)
			)
			(layer "F.Fab")
		)
		(pad "1" smd circle
			(at -0.40005 0 270)
			(size 0 0)
			(layers "F.Cu" "F.Mask" "F.Paste")
			(net "PEX0_MODE_SEL10")
		)
		(pad "2" smd circle
			(at 0.40005 0 270)
			(size 0 0)
			(layers "F.Cu" "F.Mask" "F.Paste")
			(net "P1V8_PEX")
		)
	)
	(footprint ""
		(layer "F.Cu")
		(at 382.802384 -250.070874 -90)
		(property "Reference" "R1416"
			(at 0 0 270)
			(layer "F.SilkS")
			(hide yes)
			(effects
				(font
					(size 1.27 1.27)
				)
			)
		)
		(property "Value" ""
			(at 0 0 270)
			(layer "F.Fab")
			(effects
				(font
					(size 1.27 1.27)
				)
			)
		)
		(duplicate_pad_numbers_are_jumpers no)
		(fp_line
			(start -0.7874 0.4064)
			(end -0.7874 -0.4064)
			(stroke
				(width 0.1524)
				(type default)
			)
			(layer "F.SilkS")
		)
		(fp_line
			(start 0.7874 0.4064)
			(end -0.7874 0.4064)
			(stroke
				(width 0.1524)
				(type default)
			)
			(layer "F.SilkS")
		)
		(fp_line
			(start -0.7874 -0.4064)
			(end 0.7874 -0.4064)
			(stroke
				(width 0.1524)
				(type default)
			)
			(layer "F.SilkS")
		)
		(fp_line
			(start 0.7874 -0.4064)
			(end 0.7874 0.4064)
			(stroke
				(width 0.1524)
				(type default)
			)
			(layer "F.SilkS")
		)
		(fp_line
			(start -0.67945 0.3048)
			(end -0.67945 -0.305054)
			(stroke
				(width 0.1)
				(type default)
			)
			(layer "F.Fab")
		)
		(fp_line
			(start -0.12065 0.3048)
			(end -0.67945 0.3048)
			(stroke
				(width 0.1)
				(type default)
			)
			(layer "F.Fab")
		)
		(fp_line
			(start 0.120396 0.3048)
			(end 0.120396 0.2794)
			(stroke
				(width 0.1)
				(type default)
			)
			(layer "F.Fab")
		)
		(fp_line
			(start 0.67945 0.3048)
			(end 0.120396 0.3048)
			(stroke
				(width 0.1)
				(type default)
			)
			(layer "F.Fab")
		)
		(fp_line
			(start -0.12065 0.2794)
			(end -0.12065 0.3048)
			(stroke
				(width 0.1)
				(type default)
			)
			(layer "F.Fab")
		)
		(fp_line
			(start 0.120396 0.2794)
			(end -0.12065 0.2794)
			(stroke
				(width 0.1)
				(type default)
			)
			(layer "F.Fab")
		)
		(fp_line
			(start -0.12065 -0.2794)
			(end 0.12065 -0.2794)
			(stroke
				(width 0.1)
				(type default)
			)
			(layer "F.Fab")
		)
		(fp_line
			(start 0.12065 -0.2794)
			(end 0.12065 -0.3048)
			(stroke
				(width 0.1)
				(type default)
			)
			(layer "F.Fab")
		)
		(fp_line
			(start 0.12065 -0.3048)
			(end 0.67945 -0.3048)
			(stroke
				(width 0.1)
				(type default)
			)
			(layer "F.Fab")
		)
		(fp_line
			(start 0.67945 -0.3048)
			(end 0.67945 0.3048)
			(stroke
				(width 0.1)
				(type default)
			)
			(layer "F.Fab")
		)
		(fp_line
			(start -0.67945 -0.305054)
			(end -0.12065 -0.305054)
			(stroke
				(width 0.1)
				(type default)
			)
			(layer "F.Fab")
		)
		(fp_line
			(start -0.12065 -0.305054)
			(end -0.12065 -0.2794)
			(stroke
				(width 0.1)
				(type default)
			)
			(layer "F.Fab")
		)
		(pad "1" smd circle
			(at -0.40005 0 270)
			(size 0 0)
			(layers "F.Cu" "F.Mask" "F.Paste")
			(net "PEX3_MODE_SEL11")
		)
		(pad "2" smd circle
			(at 0.40005 0 270)
			(size 0 0)
			(layers "F.Cu" "F.Mask" "F.Paste")
			(net "P1V8_PEX")
		)
	)
	(footprint ""
		(layer "F.Cu")
		(at 357.495094 -59.577986 90)
		(property "Reference" "PC555"
			(at 0 0 90)
			(layer "F.SilkS")
			(hide yes)
			(effects
				(font
					(size 1.27 1.27)
				)
			)
		)
		(property "Value" ""
			(at 0 0 90)
			(layer "F.Fab")
			(effects
				(font
					(size 1.27 1.27)
				)
			)
		)
		(duplicate_pad_numbers_are_jumpers no)
		(fp_line
			(start 0.7874 -0.4064)
			(end 0.7874 0.4064)
			(stroke
				(width 0.1524)
				(type default)
			)
			(layer "F.SilkS")
		)
		(fp_line
			(start -0.7874 -0.4064)
			(end 0.7874 -0.4064)
			(stroke
				(width 0.1524)
				(type default)
			)
			(layer "F.SilkS")
		)
		(fp_line
			(start 0.7874 0.4064)
			(end -0.7874 0.4064)
			(stroke
				(width 0.1524)
				(type default)
			)
			(layer "F.SilkS")
		)
		(fp_line
			(start -0.7874 0.4064)
			(end -0.7874 -0.4064)
			(stroke
				(width 0.1524)
				(type default)
			)
			(layer "F.SilkS")
		)
		(fp_line
			(start -0.12065 -0.305054)
			(end -0.12065 -0.2794)
			(stroke
				(width 0.1)
				(type default)
			)
			(layer "F.Fab")
		)
		(fp_line
			(start -0.67945 -0.305054)
			(end -0.12065 -0.305054)
			(stroke
				(width 0.1)
				(type default)
			)
			(layer "F.Fab")
		)
		(fp_line
			(start 0.67945 -0.3048)
			(end 0.67945 0.3048)
			(stroke
				(width 0.1)
				(type default)
			)
			(layer "F.Fab")
		)
		(fp_line
			(start 0.12065 -0.3048)
			(end 0.67945 -0.3048)
			(stroke
				(width 0.1)
				(type default)
			)
			(layer "F.Fab")
		)
		(fp_line
			(start 0.12065 -0.2794)
			(end 0.12065 -0.3048)
			(stroke
				(width 0.1)
				(type default)
			)
			(layer "F.Fab")
		)
		(fp_line
			(start -0.12065 -0.2794)
			(end 0.12065 -0.2794)
			(stroke
				(width 0.1)
				(type default)
			)
			(layer "F.Fab")
		)
		(fp_line
			(start 0.120396 0.2794)
			(end -0.12065 0.2794)
			(stroke
				(width 0.1)
				(type default)
			)
			(layer "F.Fab")
		)
		(fp_line
			(start -0.12065 0.2794)
			(end -0.12065 0.3048)
			(stroke
				(width 0.1)
				(type default)
			)
			(layer "F.Fab")
		)
		(fp_line
			(start 0.67945 0.3048)
			(end 0.120396 0.3048)
			(stroke
				(width 0.1)
				(type default)
			)
			(layer "F.Fab")
		)
		(fp_line
			(start 0.120396 0.3048)
			(end 0.120396 0.2794)
			(stroke
				(width 0.1)
				(type default)
			)
			(layer "F.Fab")
		)
		(fp_line
			(start -0.12065 0.3048)
			(end -0.67945 0.3048)
			(stroke
				(width 0.1)
				(type default)
			)
			(layer "F.Fab")
		)
		(fp_line
			(start -0.67945 0.3048)
			(end -0.67945 -0.305054)
			(stroke
				(width 0.1)
				(type default)
			)
			(layer "F.Fab")
		)
		(pad "1" smd circle
			(at -0.40005 0 90)
			(size 0 0)
			(layers "F.Cu" "F.Mask" "F.Paste")
			(net "P3V3_SSD12_SS")
		)
		(pad "2" smd circle
			(at 0.40005 0 90)
			(size 0 0)
			(layers "F.Cu" "F.Mask" "F.Paste")
			(net "GND")
		)
	)
	(footprint ""
		(layer "F.Cu")
		(at 321.322192 -102.319328 45)
		(property "Reference" "C618"
			(at 0 0 45)
			(layer "F.SilkS")
			(hide yes)
			(effects
				(font
					(size 1.27 1.27)
				)
			)
		)
		(property "Value" ""
			(at 0 0 45)
			(layer "F.Fab")
			(effects
				(font
					(size 1.27 1.27)
				)
			)
		)
		(duplicate_pad_numbers_are_jumpers no)
		(fp_line
			(start -0.787389 -0.406267)
			(end 0.787389 -0.406267)
			(stroke
				(width 0.1524)
				(type default)
			)
			(layer "F.SilkS")
		)
		(fp_line
			(start -0.787389 0.406267)
			(end -0.787389 -0.406267)
			(stroke
				(width 0.1524)
				(type default)
			)
			(layer "F.SilkS")
		)
		(fp_line
			(start 0.787389 -0.406267)
			(end 0.787389 0.406267)
			(stroke
				(width 0.1524)
				(type default)
			)
			(layer "F.SilkS")
		)
		(fp_line
			(start 0.787389 0.406267)
			(end -0.787389 0.406267)
			(stroke
				(width 0.1524)
				(type default)
			)
			(layer "F.SilkS")
		)
		(fp_line
			(start -0.679446 -0.305149)
			(end -0.120695 -0.304969)
			(stroke
				(width 0.1)
				(type default)
			)
			(layer "F.Fab")
		)
		(fp_line
			(start -0.120695 -0.304969)
			(end -0.120695 -0.279466)
			(stroke
				(width 0.1)
				(type default)
			)
			(layer "F.Fab")
		)
		(fp_line
			(start -0.120695 -0.279466)
			(end 0.120695 -0.279466)
			(stroke
				(width 0.1)
				(type default)
			)
			(layer "F.Fab")
		)
		(fp_line
			(start -0.679446 0.30479)
			(end -0.679446 -0.305149)
			(stroke
				(width 0.1)
				(type default)
			)
			(layer "F.Fab")
		)
		(fp_line
			(start 0.120515 -0.30479)
			(end 0.679446 -0.30479)
			(stroke
				(width 0.1)
				(type default)
			)
			(layer "F.Fab")
		)
		(fp_line
			(start 0.120695 -0.279466)
			(end 0.120515 -0.30479)
			(stroke
				(width 0.1)
				(type default)
			)
			(layer "F.Fab")
		)
		(fp_line
			(start -0.120695 0.279466)
			(end -0.120515 0.30479)
			(stroke
				(width 0.1)
				(type default)
			)
			(layer "F.Fab")
		)
		(fp_line
			(start -0.120515 0.30479)
			(end -0.679446 0.30479)
			(stroke
				(width 0.1)
				(type default)
			)
			(layer "F.Fab")
		)
		(fp_line
			(start 0.679446 -0.30479)
			(end 0.679446 0.30479)
			(stroke
				(width 0.1)
				(type default)
			)
			(layer "F.Fab")
		)
		(fp_line
			(start 0.120335 0.279466)
			(end -0.120695 0.279466)
			(stroke
				(width 0.1)
				(type default)
			)
			(layer "F.Fab")
		)
		(fp_line
			(start 0.120515 0.30479)
			(end 0.120335 0.279466)
			(stroke
				(width 0.1)
				(type default)
			)
			(layer "F.Fab")
		)
		(fp_line
			(start 0.679446 0.30479)
			(end 0.120515 0.30479)
			(stroke
				(width 0.1)
				(type default)
			)
			(layer "F.Fab")
		)
		(pad "1" smd circle
			(at -0.40005 0 45)
			(size 0 0)
			(layers "F.Cu" "F.Mask" "F.Paste")
			(net "P12V_NIC5_VIN_P")
		)
		(pad "2" smd circle
			(at 0.40005 0 45)
			(size 0 0)
			(layers "F.Cu" "F.Mask" "F.Paste")
			(net "P12V_NIC5_VIN_N")
		)
	)
)
